G04 ================== begin FILE IDENTIFICATION RECORD ==================*
G04 Layout Name:  DA0T6MTH8C0_t6m_tray_bp_c_brd_103112_274.brd*
G04 Film Name:    smt.art*
G04 File Format:  Gerber RS274X*
G04 File Origin:  Cadence Allegro 16.3-S048*
G04 Origin Date:  Tue Nov 26 11:26:40 2013*
G04 *
G04 Layer:  DRAWING FORMAT/TITLE_BLOCK*
G04 Layer:  VIA CLASS/SOLDERMASK_TOP*
G04 Layer:  PIN/SOLDERMASK_TOP*
G04 Layer:  PACKAGE GEOMETRY/SOLDERMASK_TOP*
G04 Layer:  MANUFACTURING/PHOTOPLOT_OUTLINE*
G04 Layer:  DRAWING FORMAT/TITLE_DATA_SMT*
G04 Layer:  BOARD GEOMETRY/SOLDERMASK_TOP*
G04 *
G04 Offset:    (0.00 0.00)*
G04 Mirror:    No*
G04 Mode:      Positive*
G04 Rotation:  0*
G04 FullContactRelief:  No*
G04 UndefLineWidth:     6.00*
G04 ================== end FILE IDENTIFICATION RECORD ====================*
%FSLAX25Y25*MOIN*%
%IR0*IPPOS*OFA0.00000B0.00000*MIA0B0*SFA1.00000B1.00000*%
%ADD15R,.036X.201*%
%ADD40C,.04*%
%ADD27C,.05*%
%ADD11C,.07*%
%ADD10C,.034*%
%ADD39C,.053*%
%ADD20C,.062*%
%ADD16C,.063*%
%ADD41C,.055*%
%ADD44R,.04X.04*%
%ADD37C,.065*%
%ADD36C,.083*%
%ADD34C,.057*%
%ADD29R,.05X.05*%
%ADD21C,.058*%
%ADD17C,.067*%
%ADD13R,.07X.07*%
%ADD47C,.096*%
%ADD45R,.055X.055*%
%ADD18R,.067X.067*%
%ADD23R,.024X.022*%
%ADD31R,.022X.024*%
%ADD22C,.12*%
%ADD30R,.032X.036*%
%ADD28C,.105*%
%ADD42C,.124*%
%ADD35O,.024X.084*%
%ADD25C,.232*%
%ADD50R,.107X.193*%
%ADD46C,.143*%
%ADD12C,.162*%
%ADD24C,.217*%
%ADD49R,.04X.088*%
%ADD33R,.044X.075*%
%ADD19R,.377X.252*%
%ADD43C,.148*%
%ADD38O,.058X.083*%
%ADD14C,.158*%
%ADD48R,.019X.077*%
%ADD26R,.058X.048*%
%ADD32R,.048X.058*%
%ADD51C,.02*%
%ADD52C,.006*%
%ADD53C,.1782*%
G75*
%LPD*%
G75*
G36*
G01X35667Y18504D02*
G02I-17950J0D01*
G37*
G36*
G01X33664Y114173D02*
G02X1768I-15948J0D01*
G01Y137795D01*
G02X33664I15948J0D01*
G01Y114173D01*
G37*
G36*
G01X35626Y184006D02*
Y209843D01*
X6926D01*
Y184006D01*
X35626D01*
G37*
G36*
G01X201441Y178895D02*
Y209895D01*
X43632D01*
Y178895D01*
X201441D01*
G37*
G36*
G01X330161Y163386D02*
G02X298265I-15948J0D01*
G01Y187008D01*
G02X330161I15948J0D01*
G01Y163386D01*
G37*
G36*
G01X633670Y78186D02*
Y104044D01*
X632067D01*
Y113244D01*
X633670D01*
Y163044D01*
X632067D01*
Y172244D01*
X633670D01*
Y198586D01*
X799306D01*
Y172244D01*
X800888D01*
Y163044D01*
X799306D01*
Y113144D01*
X800888D01*
Y104044D01*
X799306D01*
Y78186D01*
X771695D01*
Y86893D01*
X788788D01*
X788764Y103344D01*
X786488D01*
Y113944D01*
X788749D01*
X788728Y128444D01*
X786888D01*
Y136144D01*
X788716D01*
X788679Y162444D01*
X786488D01*
Y172744D01*
X788664D01*
X788651Y181650D01*
X719188D01*
Y86893D01*
X737795D01*
Y78186D01*
X696695D01*
Y86893D01*
X713788D01*
Y181650D01*
X644326D01*
X644335Y172844D01*
X646488D01*
Y162544D01*
X644345D01*
Y136044D01*
X646088D01*
Y128444D01*
X644345D01*
Y113744D01*
X646488D01*
Y103444D01*
X644345D01*
Y86893D01*
X662088D01*
Y78186D01*
X633670D01*
G37*
G36*
G01X799609Y18504D02*
G02X767713I-15948J0D01*
G01Y42126D01*
G02X799609I15948J0D01*
G01Y18504D01*
G37*
G36*
G01X841972Y163386D02*
G02X810076I-15948J0D01*
G01Y187008D01*
G02X841972I15948J0D01*
G01Y163386D01*
G37*
G36*
G01X1117563Y18504D02*
G02X1085667I-15948J0D01*
G01Y42126D01*
G02X1117563I15948J0D01*
G01Y18504D01*
G37*
G36*
G01X1200240Y163386D02*
G02X1168344I-15948J0D01*
G01Y187008D01*
G02X1200240I15948J0D01*
G01Y163386D01*
G37*
G36*
G01X1503749Y78186D02*
Y104044D01*
X1502146D01*
Y113244D01*
X1503749D01*
Y163044D01*
X1502146D01*
Y172244D01*
X1503749D01*
Y198586D01*
X1669385D01*
Y172244D01*
X1670967D01*
Y163044D01*
X1669385D01*
Y113144D01*
X1670967D01*
Y104044D01*
X1669385D01*
Y78186D01*
X1641774D01*
Y86893D01*
X1658867D01*
X1658843Y103344D01*
X1656567D01*
Y113944D01*
X1658828D01*
X1658807Y128444D01*
X1656967D01*
Y136144D01*
X1658795D01*
X1658758Y162444D01*
X1656567D01*
Y172744D01*
X1658743D01*
X1658730Y181650D01*
X1589267D01*
Y86893D01*
X1607874D01*
Y78186D01*
X1566774D01*
Y86893D01*
X1583867D01*
Y181650D01*
X1514405D01*
X1514414Y172844D01*
X1516567D01*
Y162544D01*
X1514424D01*
Y136044D01*
X1516167D01*
Y128444D01*
X1514424D01*
Y113744D01*
X1516567D01*
Y103444D01*
X1514424D01*
Y86893D01*
X1532167D01*
Y78186D01*
X1503749D01*
G37*
G36*
G01X1688462Y18504D02*
G02I-17950J0D01*
G37*
%LPC*%
G75*
G36*
G01X8351Y127903D02*
G02X27081I9365J9892D01*
G03X26416Y126359I1462J-1545D01*
G01Y114173D01*
G02X9016I-8700J0D01*
G01Y126359D01*
G03X8351Y127903I-2127J-1D01*
G37*
G36*
G01X304848Y177116D02*
G02X323578I9365J9892D01*
G03X322913Y175572I1462J-1545D01*
G01Y163386D01*
G02X305513I-8700J0D01*
G01Y175572D01*
G03X304848Y177116I-2127J-1D01*
G37*
G36*
G01X774296Y32234D02*
G02X793026I9365J9892D01*
G03X792361Y30690I1462J-1545D01*
G01Y18504D01*
G02X774961I-8700J0D01*
G01Y30690D01*
G03X774296Y32234I-2127J-1D01*
G37*
G36*
G01X816659Y177116D02*
G02X835389I9365J9892D01*
G03X834724Y175572I1462J-1545D01*
G01Y163386D01*
G02X817324I-8700J0D01*
G01Y175572D01*
G03X816659Y177116I-2127J-1D01*
G37*
G36*
G01X1092250Y32234D02*
G02X1110980I9365J9892D01*
G03X1110315Y30690I1462J-1545D01*
G01Y18504D01*
G02X1092915I-8700J0D01*
G01Y30690D01*
G03X1092250Y32234I-2127J-1D01*
G37*
G36*
G01X1174927Y177116D02*
G02X1193657I9365J9892D01*
G03X1192992Y175572I1462J-1545D01*
G01Y163386D01*
G02X1175592I-8700J0D01*
G01Y175572D01*
G03X1174927Y177116I-2127J-1D01*
G37*
G54D53*
X17717Y18504D03*
X1670512D03*
%LPD*%
G75*
G54D10*
X8221Y28000D03*
Y9008D03*
X4287Y18504D03*
X17717Y5074D03*
X27213Y28000D03*
X31147Y18504D03*
X27213Y9008D03*
X17717Y31934D03*
X477630Y78800D03*
X487558Y78600D03*
X471787Y78400D03*
X496242Y78600D03*
X504842Y78684D03*
X702610Y53111D03*
X713900Y60500D03*
X707600Y57900D03*
X1341187Y78400D03*
X1348300Y78500D03*
X1357700Y78700D03*
X1364258D03*
X1376358D03*
X1572300Y53500D03*
X1579300Y57900D03*
X1586100Y60500D03*
X1661016Y28000D03*
Y9008D03*
X1657082Y18504D03*
X1670512Y5074D03*
X1680008Y28000D03*
X1683942Y18504D03*
X1680008Y9008D03*
X1670512Y31934D03*
G54D20*
X85866Y72835D03*
Y104331D03*
G54D11*
X9088Y80158D03*
Y91958D03*
X109288Y92458D03*
Y103958D03*
G54D12*
X17717Y18504D03*
X1670512D03*
G54D30*
X346524Y90099D03*
Y95899D03*
X352424Y90099D03*
Y95899D03*
X1217324Y89699D03*
Y95499D03*
X1223424D03*
Y89699D03*
G54D21*
X81929Y76772D03*
Y68898D03*
X89803Y76772D03*
Y68898D03*
X81929Y100394D03*
Y92520D03*
Y84646D03*
X89803Y100394D03*
Y92520D03*
Y84646D03*
X81929Y108268D03*
X89803D03*
G54D22*
X109400Y41000D03*
X1009700Y81500D03*
X1636400Y43200D03*
G54D31*
X350465Y108561D03*
Y102961D03*
Y114657D03*
X361285Y102961D03*
X364435D03*
X361285Y114657D03*
X364435D03*
X361285Y108561D03*
X364435D03*
X353615D03*
Y102961D03*
Y114657D03*
X460285Y87315D03*
X463435D03*
X460285Y91615D03*
X463435D03*
X460285Y95915D03*
X463435D03*
X460285Y83015D03*
X463435D03*
X460285Y104515D03*
X463435D03*
X460285Y100215D03*
X463435D03*
X474692Y91958D03*
X477842D03*
X471787Y87558D03*
X468637D03*
X471787Y83258D03*
X468637D03*
X513787Y91561D03*
X510637D03*
X513787Y95861D03*
X510637D03*
X510813Y83242D03*
X513963D03*
X510813Y87442D03*
X513963D03*
X513787Y104461D03*
X510637D03*
X513787Y100161D03*
X510637D03*
X611415Y95139D03*
X608265D03*
X611415Y90157D03*
X608265D03*
X619613D03*
X622763D03*
X619613Y95139D03*
X622763D03*
X611415Y105157D03*
X608265D03*
X611415Y100157D03*
X608265D03*
X619613D03*
X622763D03*
X619613Y105157D03*
X622763D03*
X1223263Y108361D03*
X1220113D03*
X1223263Y102861D03*
X1220113D03*
X1223263Y119561D03*
X1220113D03*
X1223263Y114043D03*
X1220113D03*
X1230985Y119561D03*
X1234135D03*
X1230985Y114043D03*
X1234135D03*
X1230985Y108361D03*
X1234135D03*
X1230985Y102861D03*
X1234135D03*
X1329637Y85839D03*
X1332787D03*
X1329637Y90339D03*
X1332787D03*
X1329637Y94639D03*
X1332787D03*
X1329737Y99239D03*
X1332887D03*
X1341187Y83258D03*
X1338037D03*
X1341187Y87558D03*
X1338037D03*
X1384287Y95861D03*
X1381137D03*
X1384163Y91561D03*
X1381013D03*
Y83042D03*
X1384163D03*
X1381013Y87242D03*
X1384163D03*
X1384287Y104461D03*
X1381137D03*
X1384287Y100161D03*
X1381137D03*
X1481215Y93057D03*
X1478065D03*
X1481215Y98057D03*
X1478065D03*
X1481215Y103257D03*
X1478065D03*
X1481215Y109357D03*
X1478065D03*
X1488313Y93057D03*
X1491463D03*
X1488313Y98057D03*
X1491463D03*
X1488313Y103257D03*
X1491463D03*
X1488313Y109357D03*
X1491463D03*
G54D13*
X19088Y80158D03*
Y91958D03*
X119288Y92458D03*
Y103958D03*
G54D40*
X466654Y7874D03*
Y29922D03*
Y24410D03*
Y18898D03*
Y13386D03*
Y51969D03*
Y46457D03*
Y40945D03*
Y35433D03*
X474528Y8268D03*
X482402Y7874D03*
X490276Y8268D03*
X474528Y30315D03*
X482402Y29922D03*
X490276Y30315D03*
X474528Y24803D03*
X482402Y24410D03*
X490276Y24803D03*
X474528Y19292D03*
X482402Y18898D03*
X490276Y19292D03*
X474528Y13780D03*
X482402Y13386D03*
X490276Y13780D03*
X474528Y52362D03*
X482402Y51969D03*
X490276Y52362D03*
X474528Y46851D03*
X482402Y46457D03*
X490276Y46851D03*
X474528Y41339D03*
X482402Y40945D03*
X490276Y41339D03*
X474528Y35827D03*
X482402Y35433D03*
X490276Y35827D03*
X498150Y7874D03*
Y29922D03*
X506024Y30315D03*
X498150Y24410D03*
X506024Y24803D03*
X498150Y18898D03*
X506024Y19292D03*
X498150Y13386D03*
X506024Y13780D03*
X498150Y51969D03*
X506024Y52362D03*
X498150Y46457D03*
X506024Y46851D03*
X498150Y40945D03*
X506024Y41339D03*
X498150Y35433D03*
X506024Y35827D03*
X649173Y7874D03*
Y29922D03*
Y24410D03*
Y18898D03*
Y13386D03*
Y51969D03*
Y46457D03*
Y40945D03*
Y35433D03*
X657047Y8268D03*
X664921Y7874D03*
X672795Y8268D03*
X657047Y30315D03*
X664921Y29922D03*
X672795Y30315D03*
X657047Y24803D03*
X664921Y24410D03*
X672795Y24803D03*
X657047Y19292D03*
X664921Y18898D03*
X672795Y19292D03*
X657047Y13780D03*
X664921Y13386D03*
X672795Y13780D03*
X657047Y52362D03*
X664921Y51969D03*
X672795Y52362D03*
X657047Y46851D03*
X664921Y46457D03*
X672795Y46851D03*
X657047Y41339D03*
X664921Y40945D03*
X672795Y41339D03*
X657047Y35827D03*
X664921Y35433D03*
X672795Y35827D03*
X680669Y7874D03*
Y29922D03*
X688543Y30315D03*
X680669Y24410D03*
X688543Y24803D03*
X680669Y18898D03*
X688543Y19292D03*
X680669Y13386D03*
X688543Y13780D03*
X680669Y51969D03*
X688543Y52362D03*
X680669Y46457D03*
X688543Y46851D03*
X680669Y40945D03*
X688543Y41339D03*
X680669Y35433D03*
X688543Y35827D03*
X1336733Y7874D03*
X1344607Y8268D03*
X1336733Y29922D03*
X1344607Y30315D03*
X1336733Y24410D03*
X1344607Y24803D03*
X1336733Y18898D03*
X1344607Y19292D03*
X1336733Y13386D03*
X1344607Y13780D03*
X1336733Y51969D03*
X1344607Y52362D03*
X1336733Y46457D03*
X1344607Y46851D03*
X1336733Y40945D03*
X1344607Y41339D03*
X1336733Y35433D03*
X1344607Y35827D03*
X1352481Y7874D03*
X1360355Y8268D03*
X1352481Y29922D03*
X1360355Y30315D03*
X1352481Y24410D03*
X1360355Y24803D03*
X1352481Y18898D03*
X1360355Y19292D03*
X1352481Y13386D03*
X1360355Y13780D03*
X1352481Y51969D03*
X1360355Y52362D03*
X1352481Y46457D03*
X1360355Y46851D03*
X1352481Y40945D03*
X1360355Y41339D03*
X1352481Y35433D03*
X1360355Y35827D03*
X1368229Y7874D03*
Y29922D03*
X1376103Y30315D03*
X1368229Y24410D03*
X1376103Y24803D03*
X1368229Y18898D03*
X1376103Y19292D03*
X1368229Y13386D03*
X1376103Y13780D03*
X1368229Y51969D03*
X1376103Y52362D03*
X1368229Y46457D03*
X1376103Y46851D03*
X1368229Y40945D03*
X1376103Y41339D03*
X1368229Y35433D03*
X1376103Y35827D03*
X1519252Y7874D03*
X1527126Y8268D03*
X1519252Y29922D03*
X1527126Y30315D03*
X1519252Y24410D03*
X1527126Y24803D03*
X1519252Y18898D03*
X1527126Y19292D03*
X1519252Y13386D03*
X1527126Y13780D03*
X1519252Y51969D03*
X1527126Y52362D03*
X1519252Y46457D03*
X1527126Y46851D03*
X1519252Y40945D03*
X1527126Y41339D03*
X1519252Y35433D03*
X1527126Y35827D03*
X1535000Y7874D03*
X1542874Y8268D03*
X1550748Y7874D03*
X1535000Y29922D03*
X1542874Y30315D03*
X1550748Y29922D03*
X1535000Y24410D03*
X1542874Y24803D03*
X1550748Y24410D03*
X1535000Y18898D03*
X1542874Y19292D03*
X1550748Y18898D03*
X1535000Y13386D03*
X1542874Y13780D03*
X1550748Y13386D03*
X1535000Y51969D03*
X1542874Y52362D03*
X1550748Y51969D03*
X1535000Y46457D03*
X1542874Y46851D03*
X1550748Y46457D03*
X1535000Y40945D03*
X1542874Y41339D03*
X1550748Y40945D03*
X1535000Y35433D03*
X1542874Y35827D03*
X1550748Y35433D03*
X1558622Y30315D03*
Y24803D03*
Y19292D03*
Y13780D03*
Y52362D03*
Y46851D03*
Y41339D03*
Y35827D03*
G54D32*
X354460Y121642D03*
Y130142D03*
X361940Y121642D03*
Y130142D03*
X618140Y120258D03*
X610660D03*
X618140Y112158D03*
X610660D03*
X1225160Y126242D03*
Y134542D03*
X1232640Y126242D03*
Y134542D03*
X1480760Y117558D03*
Y126358D03*
X1488240Y117558D03*
Y126358D03*
G54D14*
X17716Y114173D03*
X314213Y163386D03*
X783661Y18504D03*
X826024Y163386D03*
X1101615Y18504D03*
X1184292Y163386D03*
G54D50*
X1676417Y114567D03*
G54D23*
X101739Y65963D03*
Y62813D03*
X111958Y62925D03*
Y66075D03*
X121958Y62925D03*
Y66075D03*
X116958Y62925D03*
Y66075D03*
X106958Y62925D03*
Y66075D03*
X111958Y76125D03*
X121958D03*
X116958D03*
X106958D03*
X111958Y79275D03*
X121958D03*
X116958D03*
X106958D03*
X358259Y93869D03*
Y90719D03*
X362759Y93869D03*
Y90719D03*
X403600Y9925D03*
Y13075D03*
X408200Y9925D03*
Y13075D03*
X412800Y10025D03*
Y13175D03*
X417200Y10025D03*
Y13175D03*
X477630Y83278D03*
Y86428D03*
X483258Y87208D03*
Y84058D03*
X487558D03*
Y87208D03*
X496242D03*
Y84058D03*
X500558D03*
Y87208D03*
X504842Y84058D03*
Y87208D03*
X571700Y10425D03*
Y13575D03*
X567300Y10425D03*
Y13575D03*
X562800Y10425D03*
Y13575D03*
X576100Y10425D03*
Y13575D03*
X1229324Y93574D03*
Y90424D03*
X1233524Y93574D03*
Y90424D03*
X1272600Y8825D03*
Y11975D03*
X1281600Y8825D03*
Y11975D03*
X1277000Y8825D03*
Y11975D03*
X1286000Y8825D03*
Y11975D03*
X1350257Y84185D03*
Y87335D03*
X1355642Y86908D03*
Y83758D03*
X1359942D03*
Y86908D03*
X1364258Y83692D03*
Y86842D03*
X1345558Y84213D03*
Y87363D03*
X1368658Y86842D03*
Y83692D03*
X1376358Y83313D03*
Y86463D03*
X1433400Y10625D03*
Y13775D03*
X1447000Y10725D03*
Y13875D03*
X1437900Y10625D03*
Y13775D03*
X1442600Y10725D03*
Y13875D03*
G54D41*
X468859Y115666D03*
Y141650D03*
X488859Y115666D03*
X478859D03*
X483859Y125666D03*
X473859D03*
X478859Y141650D03*
X488859D03*
X473859Y151650D03*
X483859D03*
X498859Y115666D03*
X503859Y125666D03*
X493859D03*
X498859Y141650D03*
X493859Y151650D03*
X1338938Y115666D03*
X1343938Y125666D03*
X1338938Y141650D03*
X1343938Y151650D03*
X1358938Y115666D03*
X1348938D03*
X1363938Y125666D03*
X1353938D03*
X1348938Y141650D03*
X1358938D03*
X1353938Y151650D03*
X1363938D03*
X1368938Y115666D03*
X1373938Y125666D03*
X1368938Y141650D03*
G54D51*
G01X1683504Y165354D02*
Y190512D01*
G03X1675630Y198386I-7874J0D01*
G01X1503898D01*
X1502406Y198679D01*
X1501137Y199516D01*
X1500279Y200772D01*
X1499930Y202268D01*
X1499661Y203554D01*
X1498808Y204831D01*
X1497530Y205685D01*
X1496024Y205984D01*
X1468465D01*
G03X1464528Y202047I0J-3937D01*
G01Y200000D01*
G02X1460591Y196063I-3937J0D01*
G01X1401535D01*
G02X1397598Y200000I0J3937D01*
G01Y202047D01*
G03X1393661Y205984I-3937J0D01*
G01X1319173D01*
G03X1315236Y202047I0J-3937D01*
G01Y200000D01*
G02X1311299Y196063I-3937J0D01*
G01X1252244D01*
G02X1248307Y200000I0J3937D01*
G01Y202047D01*
G03X1244370Y205984I-3937J0D01*
G01X807047D01*
X805541Y205685D01*
X804263Y204831D01*
X803410Y203554D01*
X803141Y202268D01*
X802792Y200772D01*
X801934Y199516D01*
X800665Y198679D01*
X799173Y198386D01*
X633819D01*
X632327Y198679D01*
X631058Y199516D01*
X630200Y200772D01*
X629851Y202268D01*
X629582Y203554D01*
X628729Y204831D01*
X627451Y205685D01*
X625945Y205984D01*
X598386D01*
G03X594449Y202047I0J-3937D01*
G01Y200000D01*
G02X590512Y196063I-3937J0D01*
G01X531457D01*
G02X527520Y200000I0J3937D01*
G01Y202047D01*
G03X523583Y205984I-3937J0D01*
G01X449094D01*
G03X445157Y202047I0J-3937D01*
G01Y200000D01*
G02X441220Y196063I-3937J0D01*
G01X382165D01*
G02X378228Y200000I0J3937D01*
G01Y202047D01*
G03X374291Y205984I-3937J0D01*
G01X228661D01*
G03X220787Y198110I0J-7874D01*
G01Y170551D01*
G02X216850Y166614I-3937J0D01*
G01X208976D01*
G02X205039Y170551I0J3937D01*
G01Y203937D01*
X199134Y209842D01*
X49803D01*
X43898Y203937D01*
Y167913D01*
G02X41142I-1378J0D01*
G01Y203937D01*
X37205Y207874D01*
X35236Y209842D01*
X5906D01*
X3937Y207874D01*
X0Y203937D01*
Y7874D01*
G03X7874Y0I7874J0D01*
G01X1680354D01*
G03X1688228Y7874I0J7874D01*
G01Y39370D01*
G03X1686260Y41339I-1969J0D01*
G01X1685472D01*
G02X1683504Y43307I0J1968D01*
G01Y122047D01*
G03X1681535Y124016I-1969J0D01*
G01X1675236D01*
G02X1673268Y125984I0J1968D01*
G01Y161417D01*
G02X1675236Y163386I1968J1D01*
G01X1681535D01*
G03X1683504Y165354I1J1968D01*
G01X10433Y114173D02*
Y128497D01*
G02X25000I7283J9298D01*
G01Y114173D01*
G02X10433I-7284J0D01*
G01X306929Y163386D02*
Y177710D01*
G02X321496I7283J9298D01*
G01Y163386D01*
G02X306929I-7283J0D01*
G01X776772Y18504D02*
Y32533D01*
G02X790551I6889J9593D01*
G01Y18504D01*
G02X776772I-6890J0D01*
G01X819134Y163386D02*
Y177415D01*
G02X832913I6890J9593D01*
G01Y163386D01*
G02X819134I-6889J0D01*
G01X1094331Y18504D02*
Y32828D01*
G02X1108898I7283J9298D01*
G01Y18504D01*
G02X1094331I-7283J0D01*
G01X1177008Y163386D02*
Y177710D01*
G02X1191575I7284J9298D01*
G01Y163386D01*
G02X1177008I-7283J0D01*
G54D33*
X352092Y139282D03*
X351992Y149118D03*
X363509Y139282D03*
X363409Y149118D03*
X621908Y148982D03*
X610491D03*
X622013Y158618D03*
X610596D03*
X1222199Y143895D03*
X1222304Y153605D03*
X1233616Y143895D03*
X1233721Y153605D03*
X1480708Y162291D03*
X1480794Y152600D03*
X1492125Y162291D03*
X1492211Y152600D03*
G54D24*
X306772Y19685D03*
Y41850D03*
X612047Y19685D03*
Y41850D03*
X1176851Y19685D03*
Y41850D03*
X1482126Y19685D03*
Y41850D03*
G54D42*
X452875Y131650D03*
X455867Y153658D03*
X452875Y194642D03*
X516851Y140666D03*
X519843Y115666D03*
Y194642D03*
X1322954Y131650D03*
Y194642D03*
X1325946Y153658D03*
X1389922Y115666D03*
X1386930Y140666D03*
X1389922Y194642D03*
G54D15*
X8741Y194095D03*
X13741D03*
X18741D03*
X23741D03*
X28741D03*
X33741D03*
G54D52*
G01X457212Y-338900D02*
Y-343900D01*
G01X455755Y-338900D02*
X458669D01*
G01X463579Y-343900D02*
X461045D01*
Y-338900D01*
X463579D01*
G01X462565Y-341317D02*
X461045D01*
G01X466145Y-338900D02*
Y-343900D01*
X468679D01*
G01X472512Y-344067D02*
X472385Y-343983D01*
Y-343817D01*
X472512Y-343733D01*
X472639Y-343817D01*
Y-343983D01*
X472512Y-344067D01*
G01Y-341817D02*
X472385Y-341733D01*
Y-341567D01*
X472512Y-341483D01*
X472639Y-341567D01*
Y-341733D01*
X472512Y-341817D01*
G01X477295Y-345567D02*
X476662Y-344733D01*
X476345Y-343900D01*
Y-340567D01*
X476662Y-339733D01*
X477295Y-338900D01*
G01X482712D02*
X482205Y-339067D01*
X481825Y-339483D01*
X481572Y-339983D01*
X481382Y-340650D01*
X481319Y-341400D01*
X481382Y-342150D01*
X481572Y-342817D01*
X481825Y-343317D01*
X482205Y-343733D01*
X482712Y-343900D01*
X483219Y-343733D01*
X483599Y-343317D01*
X483852Y-342817D01*
X484042Y-342150D01*
X484105Y-341400D01*
X484042Y-340650D01*
X483852Y-339983D01*
X483599Y-339483D01*
X483219Y-339067D01*
X482712Y-338900D01*
G01X486419Y-342900D02*
X486799Y-343483D01*
X487305Y-343817D01*
X487875Y-343900D01*
X488382Y-343817D01*
X488889Y-343400D01*
X489205Y-342900D01*
X489269Y-342400D01*
X489142Y-341817D01*
X488699Y-341400D01*
X488255Y-341233D01*
X487685D01*
G01X488255D02*
X488635Y-340983D01*
X488952Y-340567D01*
X489079Y-340067D01*
X488952Y-339567D01*
X488635Y-339150D01*
X488065Y-338900D01*
X487495Y-338983D01*
X486925Y-339317D01*
G01X493229Y-345567D02*
X493862Y-344733D01*
X494179Y-343900D01*
Y-340567D01*
X493862Y-339733D01*
X493229Y-338900D01*
G01X496619Y-342900D02*
X496999Y-343483D01*
X497505Y-343817D01*
X498075Y-343900D01*
X498582Y-343817D01*
X499089Y-343400D01*
X499405Y-342900D01*
X499469Y-342400D01*
X499342Y-341817D01*
X498899Y-341400D01*
X498455Y-341233D01*
X497885D01*
G01X498455D02*
X498835Y-340983D01*
X499152Y-340567D01*
X499279Y-340067D01*
X499152Y-339567D01*
X498835Y-339150D01*
X498265Y-338900D01*
X497695Y-338983D01*
X497125Y-339317D01*
G01X501909Y-339733D02*
X502289Y-339233D01*
X502732Y-338983D01*
X503239Y-338900D01*
X503872Y-339067D01*
X504315Y-339483D01*
X504442Y-339983D01*
X504379Y-340483D01*
X504125Y-340900D01*
X502859Y-341733D01*
X502289Y-342317D01*
X501909Y-343150D01*
X501782Y-343900D01*
X504442D01*
G01X508085D02*
X508212Y-342817D01*
X508402Y-341900D01*
X508655Y-341067D01*
X508972Y-340150D01*
X509479Y-338900D01*
X506945D01*
G01X512489Y-342233D02*
X514135D01*
G01X517209Y-339733D02*
X517589Y-339233D01*
X518032Y-338983D01*
X518539Y-338900D01*
X519172Y-339067D01*
X519615Y-339483D01*
X519742Y-339983D01*
X519679Y-340483D01*
X519425Y-340900D01*
X518159Y-341733D01*
X517589Y-342317D01*
X517209Y-343150D01*
X517082Y-343900D01*
X519742D01*
G01X522119Y-342900D02*
X522499Y-343483D01*
X523005Y-343817D01*
X523575Y-343900D01*
X524082Y-343817D01*
X524589Y-343400D01*
X524905Y-342900D01*
X524969Y-342400D01*
X524842Y-341817D01*
X524399Y-341400D01*
X523955Y-341233D01*
X523385D01*
G01X523955D02*
X524335Y-340983D01*
X524652Y-340567D01*
X524779Y-340067D01*
X524652Y-339567D01*
X524335Y-339150D01*
X523765Y-338900D01*
X523195Y-338983D01*
X522625Y-339317D01*
G01X529372Y-343900D02*
Y-338900D01*
X527029Y-342483D01*
X530195D01*
G01X532319Y-343150D02*
X532699Y-343567D01*
X533142Y-343817D01*
X533712Y-343900D01*
X534282Y-343733D01*
X534725Y-343400D01*
X535042Y-342817D01*
X535105Y-342150D01*
X534979Y-341483D01*
X534662Y-341067D01*
X534219Y-340733D01*
X533775Y-340650D01*
X533332Y-340733D01*
X532762Y-341067D01*
X532952Y-338900D01*
X534662D01*
G01X542709Y-343900D02*
Y-338900D01*
X545115D01*
G01X544229Y-341317D02*
X542709D01*
G01X547429Y-343900D02*
X549012Y-338900D01*
X550595Y-343900D01*
G01X550025Y-342150D02*
X547999D01*
G01X552782Y-343900D02*
X555442Y-338900D01*
G01X552782D02*
X555442Y-343900D01*
G01X559212Y-344067D02*
X559085Y-343983D01*
Y-343817D01*
X559212Y-343733D01*
X559339Y-343817D01*
Y-343983D01*
X559212Y-344067D01*
G01Y-341817D02*
X559085Y-341733D01*
Y-341567D01*
X559212Y-341483D01*
X559339Y-341567D01*
Y-341733D01*
X559212Y-341817D01*
G01X563995Y-345567D02*
X563362Y-344733D01*
X563045Y-343900D01*
Y-340567D01*
X563362Y-339733D01*
X563995Y-338900D01*
G01X569412D02*
X568905Y-339067D01*
X568525Y-339483D01*
X568272Y-339983D01*
X568082Y-340650D01*
X568019Y-341400D01*
X568082Y-342150D01*
X568272Y-342817D01*
X568525Y-343317D01*
X568905Y-343733D01*
X569412Y-343900D01*
X569919Y-343733D01*
X570299Y-343317D01*
X570552Y-342817D01*
X570742Y-342150D01*
X570805Y-341400D01*
X570742Y-340650D01*
X570552Y-339983D01*
X570299Y-339483D01*
X569919Y-339067D01*
X569412Y-338900D01*
G01X573119Y-342900D02*
X573499Y-343483D01*
X574005Y-343817D01*
X574575Y-343900D01*
X575082Y-343817D01*
X575589Y-343400D01*
X575905Y-342900D01*
X575969Y-342400D01*
X575842Y-341817D01*
X575399Y-341400D01*
X574955Y-341233D01*
X574385D01*
G01X574955D02*
X575335Y-340983D01*
X575652Y-340567D01*
X575779Y-340067D01*
X575652Y-339567D01*
X575335Y-339150D01*
X574765Y-338900D01*
X574195Y-338983D01*
X573625Y-339317D01*
G01X579929Y-345567D02*
X580562Y-344733D01*
X580879Y-343900D01*
Y-340567D01*
X580562Y-339733D01*
X579929Y-338900D01*
G01X583319Y-342900D02*
X583699Y-343483D01*
X584205Y-343817D01*
X584775Y-343900D01*
X585282Y-343817D01*
X585789Y-343400D01*
X586105Y-342900D01*
X586169Y-342400D01*
X586042Y-341817D01*
X585599Y-341400D01*
X585155Y-341233D01*
X584585D01*
G01X585155D02*
X585535Y-340983D01*
X585852Y-340567D01*
X585979Y-340067D01*
X585852Y-339567D01*
X585535Y-339150D01*
X584965Y-338900D01*
X584395Y-338983D01*
X583825Y-339317D01*
G01X588735Y-343317D02*
X589179Y-343733D01*
X589685Y-343900D01*
X590192Y-343733D01*
X590635Y-343233D01*
X590952Y-342483D01*
X591079Y-341733D01*
Y-340817D01*
X590952Y-340067D01*
X590635Y-339400D01*
X590255Y-339067D01*
X589812Y-338900D01*
X589305Y-339067D01*
X588925Y-339400D01*
X588672Y-339900D01*
X588545Y-340567D01*
X588672Y-341150D01*
X588989Y-341733D01*
X589369Y-342067D01*
X589812Y-342150D01*
X590319Y-341983D01*
X590699Y-341567D01*
X591079Y-340817D01*
G01X594785Y-343900D02*
X594912Y-342817D01*
X595102Y-341900D01*
X595355Y-341067D01*
X595672Y-340150D01*
X596179Y-338900D01*
X593645D01*
G01X599189Y-342233D02*
X600835D01*
G01X603719Y-342900D02*
X604099Y-343483D01*
X604605Y-343817D01*
X605175Y-343900D01*
X605682Y-343817D01*
X606189Y-343400D01*
X606505Y-342900D01*
X606569Y-342400D01*
X606442Y-341817D01*
X605999Y-341400D01*
X605555Y-341233D01*
X604985D01*
G01X605555D02*
X605935Y-340983D01*
X606252Y-340567D01*
X606379Y-340067D01*
X606252Y-339567D01*
X605935Y-339150D01*
X605365Y-338900D01*
X604795Y-338983D01*
X604225Y-339317D01*
G01X609009Y-341817D02*
X609452Y-341233D01*
X609832Y-340900D01*
X610339Y-340733D01*
X610782Y-340900D01*
X611099Y-341233D01*
X611352Y-341733D01*
X611415Y-342317D01*
X611352Y-342817D01*
X611099Y-343317D01*
X610719Y-343733D01*
X610275Y-343900D01*
X609769Y-343733D01*
X609325Y-343233D01*
X609072Y-342483D01*
X609009Y-341650D01*
X609135Y-340567D01*
X609325Y-339983D01*
X609642Y-339400D01*
X610085Y-338983D01*
X610529Y-338900D01*
X610972Y-339067D01*
X611289Y-339483D01*
G01X615312Y-343900D02*
Y-338900D01*
X614552Y-339900D01*
G01Y-343900D02*
X616072D01*
G01X621172D02*
Y-338900D01*
X618829Y-342483D01*
X621995D01*
G01X445212Y-273900D02*
Y-348900D01*
X945212D01*
Y-273900D01*
X445212D01*
G01X640212D02*
Y-348900D01*
G01Y-323900D02*
X743212D01*
Y-298900D01*
G01X640212D02*
X743212D01*
G01Y-273900D02*
Y-348900D01*
G01X745212Y-273900D02*
Y-348900D01*
G01X750719Y-333900D02*
Y-328900D01*
X751985D01*
X752492Y-329150D01*
X752872Y-329483D01*
X753189Y-329983D01*
X753442Y-330567D01*
X753505Y-331400D01*
X753442Y-332233D01*
X753189Y-332817D01*
X752872Y-333317D01*
X752492Y-333650D01*
X751985Y-333900D01*
X750719D01*
G01X755629D02*
X757212Y-328900D01*
X758795Y-333900D01*
G01X758225Y-332150D02*
X756199D01*
G01X762312Y-328900D02*
Y-333900D01*
G01X760855Y-328900D02*
X763769D01*
G01X768679Y-333900D02*
X766145D01*
Y-328900D01*
X768679D01*
G01X767665Y-331317D02*
X766145D01*
G01X772512Y-334067D02*
X772385Y-333983D01*
Y-333817D01*
X772512Y-333733D01*
X772639Y-333817D01*
Y-333983D01*
X772512Y-334067D01*
G01Y-331817D02*
X772385Y-331733D01*
Y-331567D01*
X772512Y-331483D01*
X772639Y-331567D01*
Y-331733D01*
X772512Y-331817D01*
G01X745212Y-323900D02*
X945212D01*
G01X750845Y-308900D02*
Y-303900D01*
X752365D01*
X752872Y-304150D01*
X753252Y-304733D01*
X753379Y-305400D01*
X753252Y-306067D01*
X752935Y-306567D01*
X752365Y-306817D01*
X750845D01*
G01X756072Y-309067D02*
X758352Y-303900D01*
G01X760855Y-308900D02*
Y-303900D01*
X763769Y-308900D01*
Y-303900D01*
G01X767412Y-309067D02*
X767285Y-308983D01*
Y-308817D01*
X767412Y-308733D01*
X767539Y-308817D01*
Y-308983D01*
X767412Y-309067D01*
G01Y-306817D02*
X767285Y-306733D01*
Y-306567D01*
X767412Y-306483D01*
X767539Y-306567D01*
Y-306733D01*
X767412Y-306817D01*
G01X745212Y-298900D02*
X945212D01*
G01X750845Y-283900D02*
Y-278900D01*
X752365D01*
X752872Y-279150D01*
X753252Y-279733D01*
X753379Y-280400D01*
X753252Y-281067D01*
X752935Y-281567D01*
X752365Y-281817D01*
X750845D01*
G01X755945Y-283900D02*
Y-278900D01*
X757529D01*
X758035Y-279150D01*
X758352Y-279483D01*
X758479Y-280150D01*
X758352Y-280817D01*
X757972Y-281233D01*
X757529Y-281483D01*
X755945D01*
G01X757529D02*
X758479Y-283900D01*
G01X762312D02*
X761805Y-283817D01*
X761362Y-283483D01*
X760982Y-282983D01*
X760729Y-282400D01*
X760602Y-281733D01*
Y-281067D01*
X760729Y-280400D01*
X760982Y-279817D01*
X761362Y-279317D01*
X761805Y-278983D01*
X762312Y-278900D01*
X762819Y-278983D01*
X763262Y-279317D01*
X763642Y-279817D01*
X763895Y-280400D01*
X764022Y-281067D01*
Y-281733D01*
X763895Y-282400D01*
X763642Y-282983D01*
X763262Y-283483D01*
X762819Y-283817D01*
X762312Y-283900D01*
G01X766145Y-282900D02*
X766462Y-283400D01*
X766842Y-283733D01*
X767285Y-283900D01*
X767792Y-283733D01*
X768172Y-283400D01*
X768552Y-282900D01*
X768679Y-282233D01*
Y-278900D01*
G01X773779Y-283900D02*
X771245D01*
Y-278900D01*
X773779D01*
G01X772765Y-281317D02*
X771245D01*
G01X779005Y-279317D02*
X778625Y-279067D01*
X778182Y-278900D01*
X777675D01*
X777105Y-279150D01*
X776662Y-279567D01*
X776345Y-280067D01*
X776092Y-280900D01*
X776029Y-281650D01*
X776155Y-282400D01*
X776345Y-282900D01*
X776725Y-283400D01*
X777169Y-283733D01*
X777612Y-283900D01*
X778055D01*
X778499Y-283733D01*
X778879Y-283483D01*
X779195Y-283150D01*
G01X782712Y-278900D02*
Y-283900D01*
G01X781255Y-278900D02*
X784169D01*
G01X787812Y-284067D02*
X787685Y-283983D01*
Y-283817D01*
X787812Y-283733D01*
X787939Y-283817D01*
Y-283983D01*
X787812Y-284067D01*
G01Y-281817D02*
X787685Y-281733D01*
Y-281567D01*
X787812Y-281483D01*
X787939Y-281567D01*
Y-281733D01*
X787812Y-281817D01*
G01X860212Y-323900D02*
Y-348900D01*
G01X865845Y-333900D02*
Y-328900D01*
X867429D01*
X867935Y-329150D01*
X868252Y-329483D01*
X868379Y-330150D01*
X868252Y-330817D01*
X867872Y-331233D01*
X867429Y-331483D01*
X865845D01*
G01X867429D02*
X868379Y-333900D01*
G01X873479D02*
X870945D01*
Y-328900D01*
X873479D01*
G01X872465Y-331317D02*
X870945D01*
G01X875729Y-328900D02*
X877312Y-333900D01*
X878895Y-328900D01*
G01X882412Y-334067D02*
X882285Y-333983D01*
Y-333817D01*
X882412Y-333733D01*
X882539Y-333817D01*
Y-333983D01*
X882412Y-334067D01*
G01Y-331817D02*
X882285Y-331733D01*
Y-331567D01*
X882412Y-331483D01*
X882539Y-331567D01*
Y-331733D01*
X882412Y-331817D01*
G01X909212Y-323900D02*
Y-348900D01*
G01X-471400Y-391900D02*
Y1528800D01*
X2244200D01*
Y-391900D01*
X-471400D01*
G01X455917Y-335560D02*
X456544Y-336085D01*
X457249Y-336400D01*
X457875D01*
X458502Y-336085D01*
X458972Y-335560D01*
X459207Y-334825D01*
X459050Y-334090D01*
X458659Y-333460D01*
X457954Y-333040D01*
X457014Y-332830D01*
X456465Y-332410D01*
X456230Y-331675D01*
X456387Y-330940D01*
X456779Y-330415D01*
X457327Y-330100D01*
X457875D01*
X458424Y-330310D01*
X458894Y-330835D01*
G01X462217Y-336400D02*
Y-330100D01*
G01X465507D02*
Y-336400D01*
G01Y-333250D02*
X462217D01*
G01X469222Y-330100D02*
X471102D01*
G01X470162D02*
Y-336400D01*
G01X469222D02*
X471102D01*
G01X478029D02*
X474895D01*
Y-330100D01*
X478029D01*
G01X476775Y-333145D02*
X474895D01*
G01X480960Y-336400D02*
Y-330100D01*
X484564Y-336400D01*
Y-330100D01*
G01X488905Y-337555D02*
X489219Y-336190D01*
G01X495362Y-330100D02*
Y-336400D01*
G01X493560Y-330100D02*
X497164D01*
G01X499704Y-336400D02*
X501662Y-330100D01*
X503620Y-336400D01*
G01X502915Y-334195D02*
X500409D01*
G01X507022Y-330100D02*
X508902D01*
G01X507962D02*
Y-336400D01*
G01X507022D02*
X508902D01*
G01X511912Y-330100D02*
X513009Y-336400D01*
X514262Y-330100D01*
X515515Y-336400D01*
X516612Y-330100D01*
G01X518604Y-336400D02*
X520562Y-330100D01*
X522520Y-336400D01*
G01X521815Y-334195D02*
X519309D01*
G01X525060Y-336400D02*
Y-330100D01*
X528664Y-336400D01*
Y-330100D01*
G01X537895Y-336400D02*
Y-330100D01*
X539854D01*
X540480Y-330415D01*
X540872Y-330835D01*
X541029Y-331675D01*
X540872Y-332515D01*
X540402Y-333040D01*
X539854Y-333355D01*
X537895D01*
G01X539854D02*
X541029Y-336400D01*
G01X545762Y-336610D02*
X545605Y-336505D01*
Y-336295D01*
X545762Y-336190D01*
X545919Y-336295D01*
Y-336505D01*
X545762Y-336610D01*
G01X552062Y-336400D02*
X551435Y-336295D01*
X550887Y-335875D01*
X550417Y-335245D01*
X550104Y-334510D01*
X549947Y-333670D01*
Y-332830D01*
X550104Y-331990D01*
X550417Y-331255D01*
X550887Y-330625D01*
X551435Y-330205D01*
X552062Y-330100D01*
X552689Y-330205D01*
X553237Y-330625D01*
X553707Y-331255D01*
X554020Y-331990D01*
X554177Y-332830D01*
Y-333670D01*
X554020Y-334510D01*
X553707Y-335245D01*
X553237Y-335875D01*
X552689Y-336295D01*
X552062Y-336400D01*
G01X558362Y-336610D02*
X558205Y-336505D01*
Y-336295D01*
X558362Y-336190D01*
X558519Y-336295D01*
Y-336505D01*
X558362Y-336610D01*
G01X566385Y-330625D02*
X565915Y-330310D01*
X565367Y-330100D01*
X564740D01*
X564035Y-330415D01*
X563487Y-330940D01*
X563095Y-331570D01*
X562782Y-332620D01*
X562704Y-333565D01*
X562860Y-334510D01*
X563095Y-335140D01*
X563565Y-335770D01*
X564114Y-336190D01*
X564662Y-336400D01*
X565210D01*
X565759Y-336190D01*
X566229Y-335875D01*
X566620Y-335455D01*
G01X570962Y-336610D02*
X570805Y-336505D01*
Y-336295D01*
X570962Y-336190D01*
X571119Y-336295D01*
Y-336505D01*
X570962Y-336610D01*
G01X455839Y-326400D02*
Y-320100D01*
G01X458815D02*
X455839Y-323985D01*
G01X459285Y-326400D02*
X457170Y-322200D01*
G01X462139Y-320100D02*
Y-324615D01*
X462452Y-325560D01*
X463079Y-326190D01*
X463862Y-326400D01*
X464645Y-326190D01*
X465272Y-325560D01*
X465585Y-324615D01*
Y-320100D01*
G01X471729Y-326400D02*
X468595D01*
Y-320100D01*
X471729D01*
G01X470475Y-323145D02*
X468595D01*
G01X475522Y-320100D02*
X477402D01*
G01X476462D02*
Y-326400D01*
G01X475522D02*
X477402D01*
G01X487417Y-325560D02*
X488044Y-326085D01*
X488749Y-326400D01*
X489375D01*
X490002Y-326085D01*
X490472Y-325560D01*
X490707Y-324825D01*
X490550Y-324090D01*
X490159Y-323460D01*
X489454Y-323040D01*
X488514Y-322830D01*
X487965Y-322410D01*
X487730Y-321675D01*
X487887Y-320940D01*
X488279Y-320415D01*
X488827Y-320100D01*
X489375D01*
X489924Y-320310D01*
X490394Y-320835D01*
G01X493717Y-326400D02*
Y-320100D01*
G01X497007D02*
Y-326400D01*
G01Y-323250D02*
X493717D01*
G01X499704Y-326400D02*
X501662Y-320100D01*
X503620Y-326400D01*
G01X502915Y-324195D02*
X500409D01*
G01X506160Y-326400D02*
Y-320100D01*
X509764Y-326400D01*
Y-320100D01*
G01X518917Y-326400D02*
Y-320100D01*
G01X522207D02*
Y-326400D01*
G01Y-323250D02*
X518917D01*
G01X525217Y-325560D02*
X525844Y-326085D01*
X526549Y-326400D01*
X527175D01*
X527802Y-326085D01*
X528272Y-325560D01*
X528507Y-324825D01*
X528350Y-324090D01*
X527959Y-323460D01*
X527254Y-323040D01*
X526314Y-322830D01*
X525765Y-322410D01*
X525530Y-321675D01*
X525687Y-320940D01*
X526079Y-320415D01*
X526627Y-320100D01*
X527175D01*
X527724Y-320310D01*
X528194Y-320835D01*
G01X532222Y-320100D02*
X534102D01*
G01X533162D02*
Y-326400D01*
G01X532222D02*
X534102D01*
G01X537504D02*
X539462Y-320100D01*
X541420Y-326400D01*
G01X540715Y-324195D02*
X538209D01*
G01X543960Y-326400D02*
Y-320100D01*
X547564Y-326400D01*
Y-320100D01*
G01X552532Y-323250D02*
X554099D01*
Y-325140D01*
X553629Y-325770D01*
X553080Y-326190D01*
X552297Y-326400D01*
X551514Y-326190D01*
X550965Y-325770D01*
X550495Y-325140D01*
X550182Y-324405D01*
X550025Y-323565D01*
Y-322830D01*
X550182Y-322200D01*
X550495Y-321465D01*
X550965Y-320835D01*
X551435Y-320415D01*
X552062Y-320100D01*
X552610D01*
X553237Y-320310D01*
X553707Y-320730D01*
G01X558205Y-327555D02*
X558519Y-326190D01*
G01X564662Y-320100D02*
Y-326400D01*
G01X562860Y-320100D02*
X566464D01*
G01X569004Y-326400D02*
X570962Y-320100D01*
X572920Y-326400D01*
G01X572215Y-324195D02*
X569709D01*
G01X577262Y-326400D02*
X576635Y-326295D01*
X576087Y-325875D01*
X575617Y-325245D01*
X575304Y-324510D01*
X575147Y-323670D01*
Y-322830D01*
X575304Y-321990D01*
X575617Y-321255D01*
X576087Y-320625D01*
X576635Y-320205D01*
X577262Y-320100D01*
X577889Y-320205D01*
X578437Y-320625D01*
X578907Y-321255D01*
X579220Y-321990D01*
X579377Y-322830D01*
Y-323670D01*
X579220Y-324510D01*
X578907Y-325245D01*
X578437Y-325875D01*
X577889Y-326295D01*
X577262Y-326400D01*
G01X589862D02*
Y-323565D01*
X588295Y-320100D01*
G01X591429D02*
X589862Y-323565D01*
G01X594439Y-320100D02*
Y-324615D01*
X594752Y-325560D01*
X595379Y-326190D01*
X596162Y-326400D01*
X596945Y-326190D01*
X597572Y-325560D01*
X597885Y-324615D01*
Y-320100D01*
G01X600504Y-326400D02*
X602462Y-320100D01*
X604420Y-326400D01*
G01X603715Y-324195D02*
X601209D01*
G01X606960Y-326400D02*
Y-320100D01*
X610564Y-326400D01*
Y-320100D01*
G01X455760Y-316400D02*
Y-310100D01*
X459364Y-316400D01*
Y-310100D01*
G01X463862Y-316400D02*
X463235Y-316295D01*
X462687Y-315875D01*
X462217Y-315245D01*
X461904Y-314510D01*
X461747Y-313670D01*
Y-312830D01*
X461904Y-311990D01*
X462217Y-311255D01*
X462687Y-310625D01*
X463235Y-310205D01*
X463862Y-310100D01*
X464489Y-310205D01*
X465037Y-310625D01*
X465507Y-311255D01*
X465820Y-311990D01*
X465977Y-312830D01*
Y-313670D01*
X465820Y-314510D01*
X465507Y-315245D01*
X465037Y-315875D01*
X464489Y-316295D01*
X463862Y-316400D01*
G01X470162Y-316610D02*
X470005Y-316505D01*
Y-316295D01*
X470162Y-316190D01*
X470319Y-316295D01*
Y-316505D01*
X470162Y-316610D01*
G01X476462Y-316400D02*
Y-310100D01*
X475522Y-311360D01*
G01Y-316400D02*
X477402D01*
G01X482762D02*
X483310Y-316295D01*
X483937Y-315980D01*
X484329Y-315455D01*
X484485Y-314720D01*
X484329Y-313985D01*
X483859Y-313355D01*
X483154Y-313040D01*
X482370D01*
X481900Y-312830D01*
X481509Y-312305D01*
X481352Y-311570D01*
X481587Y-310835D01*
X482135Y-310310D01*
X482762Y-310100D01*
X483389Y-310310D01*
X483937Y-310835D01*
X484172Y-311570D01*
X484015Y-312305D01*
X483624Y-312830D01*
X483154Y-313040D01*
X482370D01*
X481665Y-313355D01*
X481195Y-313985D01*
X481039Y-314720D01*
X481195Y-315455D01*
X481587Y-315980D01*
X482214Y-316295D01*
X482762Y-316400D01*
G01X489062D02*
X489610Y-316295D01*
X490237Y-315980D01*
X490629Y-315455D01*
X490785Y-314720D01*
X490629Y-313985D01*
X490159Y-313355D01*
X489454Y-313040D01*
X488670D01*
X488200Y-312830D01*
X487809Y-312305D01*
X487652Y-311570D01*
X487887Y-310835D01*
X488435Y-310310D01*
X489062Y-310100D01*
X489689Y-310310D01*
X490237Y-310835D01*
X490472Y-311570D01*
X490315Y-312305D01*
X489924Y-312830D01*
X489454Y-313040D01*
X488670D01*
X487965Y-313355D01*
X487495Y-313985D01*
X487339Y-314720D01*
X487495Y-315455D01*
X487887Y-315980D01*
X488514Y-316295D01*
X489062Y-316400D01*
G01X495205Y-317555D02*
X495519Y-316190D01*
G01X499312Y-310100D02*
X500409Y-316400D01*
X501662Y-310100D01*
X502915Y-316400D01*
X504012Y-310100D01*
G01X509529Y-316400D02*
X506395D01*
Y-310100D01*
X509529D01*
G01X508275Y-313145D02*
X506395D01*
G01X512460Y-316400D02*
Y-310100D01*
X516064Y-316400D01*
Y-310100D01*
G01X525217Y-316400D02*
Y-310100D01*
G01X528507D02*
Y-316400D01*
G01Y-313250D02*
X525217D01*
G01X530812Y-310100D02*
X531909Y-316400D01*
X533162Y-310100D01*
X534415Y-316400D01*
X535512Y-310100D01*
G01X537504Y-316400D02*
X539462Y-310100D01*
X541420Y-316400D01*
G01X540715Y-314195D02*
X538209D01*
G01X550574Y-311150D02*
X551044Y-310520D01*
X551592Y-310205D01*
X552219Y-310100D01*
X553002Y-310310D01*
X553550Y-310835D01*
X553707Y-311465D01*
X553629Y-312095D01*
X553315Y-312620D01*
X551749Y-313670D01*
X551044Y-314405D01*
X550574Y-315455D01*
X550417Y-316400D01*
X553707D01*
G01X556560D02*
Y-310100D01*
X560164Y-316400D01*
Y-310100D01*
G01X562939Y-316400D02*
Y-310100D01*
X564505D01*
X565132Y-310415D01*
X565602Y-310835D01*
X565994Y-311465D01*
X566307Y-312200D01*
X566385Y-313250D01*
X566307Y-314300D01*
X565994Y-315035D01*
X565602Y-315665D01*
X565132Y-316085D01*
X564505Y-316400D01*
X562939D01*
G01X575695D02*
Y-310100D01*
X577654D01*
X578280Y-310415D01*
X578672Y-310835D01*
X578829Y-311675D01*
X578672Y-312515D01*
X578202Y-313040D01*
X577654Y-313355D01*
X575695D01*
G01X577654D02*
X578829Y-316400D01*
G01X581839D02*
Y-310100D01*
X583405D01*
X584032Y-310415D01*
X584502Y-310835D01*
X584894Y-311465D01*
X585207Y-312200D01*
X585285Y-313250D01*
X585207Y-314300D01*
X584894Y-315035D01*
X584502Y-315665D01*
X584032Y-316085D01*
X583405Y-316400D01*
X581839D01*
G01X589862Y-316610D02*
X589705Y-316505D01*
Y-316295D01*
X589862Y-316190D01*
X590019Y-316295D01*
Y-316505D01*
X589862Y-316610D01*
G01X479862Y-303700D02*
X477342Y-303283D01*
X475137Y-301617D01*
X473247Y-299117D01*
X471987Y-296200D01*
X471357Y-292867D01*
Y-289533D01*
X471987Y-286200D01*
X473247Y-283283D01*
X475137Y-280784D01*
X477342Y-279117D01*
X479862Y-278700D01*
X482382Y-279117D01*
X484587Y-280784D01*
X486477Y-283283D01*
X487737Y-286200D01*
X488367Y-289533D01*
Y-292867D01*
X487737Y-296200D01*
X486477Y-299117D01*
X484587Y-301617D01*
X482382Y-303283D01*
X479862Y-303700D01*
G01X482382Y-297033D02*
X486162Y-303700D01*
G01X499707Y-287034D02*
Y-298700D01*
X500967Y-301617D01*
X502857Y-303283D01*
X505062Y-303700D01*
X507267Y-303283D01*
X509157Y-301617D01*
X510417Y-298700D01*
G01Y-303700D02*
Y-287034D01*
G01X535932Y-303700D02*
Y-287034D01*
G01Y-289950D02*
X534672Y-288284D01*
X532782Y-287450D01*
X530577Y-287034D01*
X528372Y-287867D01*
X526482Y-289533D01*
X525222Y-292034D01*
X524592Y-295367D01*
X525222Y-298700D01*
X526482Y-301201D01*
X528372Y-302867D01*
X530577Y-303700D01*
X532782Y-303283D01*
X534672Y-302034D01*
X535932Y-300367D01*
G01X550107Y-303700D02*
Y-287034D01*
G01Y-291200D02*
X551367Y-289117D01*
X553257Y-287450D01*
X555777Y-287034D01*
X557982Y-287450D01*
X559872Y-289117D01*
X560817Y-292034D01*
Y-303700D01*
G01X580662Y-278700D02*
Y-303700D01*
G01X576252Y-287034D02*
X585072D01*
G01X611532Y-303700D02*
Y-287034D01*
G01Y-289950D02*
X610272Y-288284D01*
X608382Y-287450D01*
X606177Y-287034D01*
X603972Y-287867D01*
X602082Y-289533D01*
X600822Y-292034D01*
X600192Y-295367D01*
X600822Y-298700D01*
X602082Y-301201D01*
X603972Y-302867D01*
X606177Y-303700D01*
X608382Y-303283D01*
X610272Y-302034D01*
X611532Y-300367D01*
G01X651212Y-283400D02*
Y-291400D01*
X655212D01*
G01X663012D02*
Y-286067D01*
G01Y-287000D02*
X662612Y-286467D01*
X662012Y-286200D01*
X661312Y-286067D01*
X660612Y-286333D01*
X660012Y-286867D01*
X659612Y-287667D01*
X659412Y-288733D01*
X659612Y-289800D01*
X660012Y-290600D01*
X660612Y-291133D01*
X661312Y-291400D01*
X662012Y-291267D01*
X662612Y-290867D01*
X663012Y-290334D01*
G01X667112Y-293800D02*
X667712Y-294067D01*
X668512Y-293800D01*
X669012Y-293267D01*
X669412Y-292600D01*
X670012Y-290467D01*
X671312Y-286067D01*
G01X668112D02*
X670012Y-290467D01*
G01X675712Y-287800D02*
X678912D01*
X678612Y-286867D01*
X678112Y-286333D01*
X677412Y-286067D01*
X676712Y-286200D01*
X676112Y-286600D01*
X675712Y-287533D01*
X675512Y-288334D01*
Y-289133D01*
X675712Y-289933D01*
X676212Y-290733D01*
X676812Y-291267D01*
X677512Y-291400D01*
X678212Y-291133D01*
X678912Y-290334D01*
G01X683812Y-291400D02*
Y-286067D01*
G01Y-287133D02*
X684312Y-286600D01*
X684812Y-286200D01*
X685512Y-286067D01*
X686012Y-286200D01*
X686612Y-286600D01*
G01X673512Y-333400D02*
X675912D01*
G01X674712D02*
Y-341400D01*
G01X673512D02*
X675912D01*
G01X681312D02*
Y-336067D01*
G01Y-337133D02*
X681812Y-336600D01*
X682312Y-336200D01*
X683012Y-336067D01*
X683512Y-336200D01*
X684112Y-336600D01*
G01X689212Y-337800D02*
X692412D01*
X692112Y-336867D01*
X691612Y-336333D01*
X690912Y-336067D01*
X690212Y-336200D01*
X689612Y-336600D01*
X689212Y-337533D01*
X689012Y-338334D01*
Y-339133D01*
X689212Y-339933D01*
X689712Y-340733D01*
X690312Y-341267D01*
X691012Y-341400D01*
X691712Y-341133D01*
X692412Y-340334D01*
G01X697012Y-341400D02*
Y-336067D01*
G01Y-337400D02*
X697412Y-336733D01*
X698012Y-336200D01*
X698812Y-336067D01*
X699512Y-336200D01*
X700112Y-336733D01*
X700412Y-337667D01*
Y-341400D01*
G01X705212Y-337800D02*
X708412D01*
X708112Y-336867D01*
X707612Y-336333D01*
X706912Y-336067D01*
X706212Y-336200D01*
X705612Y-336600D01*
X705212Y-337533D01*
X705012Y-338334D01*
Y-339133D01*
X705212Y-339933D01*
X705712Y-340733D01*
X706312Y-341267D01*
X707012Y-341400D01*
X707712Y-341133D01*
X708412Y-340334D01*
G01X664612Y-316400D02*
Y-308400D01*
X667212Y-315067D01*
X669812Y-308400D01*
Y-316400D01*
G01X672712D02*
X675212Y-308400D01*
X677712Y-316400D01*
G01X676812Y-313600D02*
X673612D01*
G01X681112Y-315334D02*
X681912Y-316000D01*
X682812Y-316400D01*
X683612D01*
X684412Y-316000D01*
X685012Y-315334D01*
X685312Y-314400D01*
X685112Y-313467D01*
X684612Y-312667D01*
X683712Y-312133D01*
X682512Y-311867D01*
X681812Y-311333D01*
X681512Y-310400D01*
X681712Y-309467D01*
X682212Y-308800D01*
X682912Y-308400D01*
X683612D01*
X684312Y-308667D01*
X684912Y-309333D01*
G01X689012Y-316400D02*
Y-308400D01*
G01X692812D02*
X689012Y-313334D01*
G01X693412Y-316400D02*
X690712Y-311067D01*
G01X697912Y-313733D02*
X700512D01*
G01X707212Y-308400D02*
Y-316400D01*
G01X704912Y-308400D02*
X709512D01*
G01X715212Y-316400D02*
X714412Y-316267D01*
X713712Y-315733D01*
X713112Y-314933D01*
X712712Y-314000D01*
X712512Y-312933D01*
Y-311867D01*
X712712Y-310800D01*
X713112Y-309867D01*
X713712Y-309067D01*
X714412Y-308533D01*
X715212Y-308400D01*
X716012Y-308533D01*
X716712Y-309067D01*
X717312Y-309867D01*
X717712Y-310800D01*
X717912Y-311867D01*
Y-312933D01*
X717712Y-314000D01*
X717312Y-314933D01*
X716712Y-315733D01*
X716012Y-316267D01*
X715212Y-316400D01*
G01X721212D02*
Y-308400D01*
X723612D01*
X724412Y-308800D01*
X725012Y-309733D01*
X725212Y-310800D01*
X725012Y-311867D01*
X724512Y-312667D01*
X723612Y-313067D01*
X721212D01*
G01X777812Y-334733D02*
X778412Y-333933D01*
X779112Y-333533D01*
X779912Y-333400D01*
X780912Y-333667D01*
X781612Y-334333D01*
X781812Y-335133D01*
X781712Y-335934D01*
X781312Y-336600D01*
X779312Y-337933D01*
X778412Y-338867D01*
X777812Y-340200D01*
X777612Y-341400D01*
X781812D01*
G01X787712Y-333400D02*
X786912Y-333667D01*
X786312Y-334333D01*
X785912Y-335133D01*
X785612Y-336200D01*
X785512Y-337400D01*
X785612Y-338600D01*
X785912Y-339667D01*
X786312Y-340467D01*
X786912Y-341133D01*
X787712Y-341400D01*
X788512Y-341133D01*
X789112Y-340467D01*
X789512Y-339667D01*
X789812Y-338600D01*
X789912Y-337400D01*
X789812Y-336200D01*
X789512Y-335133D01*
X789112Y-334333D01*
X788512Y-333667D01*
X787712Y-333400D01*
G01X795712Y-341400D02*
Y-333400D01*
X794512Y-335000D01*
G01Y-341400D02*
X796912D01*
G01X801812Y-334733D02*
X802412Y-333933D01*
X803112Y-333533D01*
X803912Y-333400D01*
X804912Y-333667D01*
X805612Y-334333D01*
X805812Y-335133D01*
X805712Y-335934D01*
X805312Y-336600D01*
X803312Y-337933D01*
X802412Y-338867D01*
X801812Y-340200D01*
X801612Y-341400D01*
X805812D01*
G01X809912Y-341667D02*
X813512Y-333400D01*
G01X819712Y-341400D02*
Y-333400D01*
X818512Y-335000D01*
G01Y-341400D02*
X820912D01*
G01X827712Y-333400D02*
X826912Y-333667D01*
X826312Y-334333D01*
X825912Y-335133D01*
X825612Y-336200D01*
X825512Y-337400D01*
X825612Y-338600D01*
X825912Y-339667D01*
X826312Y-340467D01*
X826912Y-341133D01*
X827712Y-341400D01*
X828512Y-341133D01*
X829112Y-340467D01*
X829512Y-339667D01*
X829812Y-338600D01*
X829912Y-337400D01*
X829812Y-336200D01*
X829512Y-335133D01*
X829112Y-334333D01*
X828512Y-333667D01*
X827712Y-333400D01*
G01X833912Y-341667D02*
X837512Y-333400D01*
G01X841512Y-339800D02*
X842112Y-340733D01*
X842912Y-341267D01*
X843812Y-341400D01*
X844612Y-341267D01*
X845412Y-340600D01*
X845912Y-339800D01*
X846012Y-339000D01*
X845812Y-338067D01*
X845112Y-337400D01*
X844412Y-337133D01*
X843512D01*
G01X844412D02*
X845012Y-336733D01*
X845512Y-336067D01*
X845712Y-335267D01*
X845512Y-334467D01*
X845012Y-333800D01*
X844112Y-333400D01*
X843212Y-333533D01*
X842312Y-334067D01*
G01X851712Y-341400D02*
Y-333400D01*
X850512Y-335000D01*
G01Y-341400D02*
X852912D01*
G01X777512Y-316400D02*
Y-308400D01*
X779512D01*
X780312Y-308800D01*
X780912Y-309333D01*
X781412Y-310133D01*
X781812Y-311067D01*
X781912Y-312400D01*
X781812Y-313733D01*
X781412Y-314667D01*
X780912Y-315467D01*
X780312Y-316000D01*
X779512Y-316400D01*
X777512D01*
G01X785212D02*
X787712Y-308400D01*
X790212Y-316400D01*
G01X789312Y-313600D02*
X786112D01*
G01X795712Y-308400D02*
X794912Y-308667D01*
X794312Y-309333D01*
X793912Y-310133D01*
X793612Y-311200D01*
X793512Y-312400D01*
X793612Y-313600D01*
X793912Y-314667D01*
X794312Y-315467D01*
X794912Y-316133D01*
X795712Y-316400D01*
X796512Y-316133D01*
X797112Y-315467D01*
X797512Y-314667D01*
X797812Y-313600D01*
X797912Y-312400D01*
X797812Y-311200D01*
X797512Y-310133D01*
X797112Y-309333D01*
X796512Y-308667D01*
X795712Y-308400D01*
G01X803712D02*
Y-316400D01*
G01X801412Y-308400D02*
X806012D01*
G01X809812Y-313067D02*
X810512Y-312133D01*
X811112Y-311600D01*
X811912Y-311333D01*
X812612Y-311600D01*
X813112Y-312133D01*
X813512Y-312933D01*
X813612Y-313867D01*
X813512Y-314667D01*
X813112Y-315467D01*
X812512Y-316133D01*
X811812Y-316400D01*
X811012Y-316133D01*
X810312Y-315334D01*
X809912Y-314133D01*
X809812Y-312800D01*
X810012Y-311067D01*
X810312Y-310133D01*
X810812Y-309200D01*
X811512Y-308533D01*
X812212Y-308400D01*
X812912Y-308667D01*
X813412Y-309333D01*
G01X817112Y-316400D02*
Y-308400D01*
X819712Y-315067D01*
X822312Y-308400D01*
Y-316400D01*
G01X827712Y-308400D02*
Y-316400D01*
G01X825412Y-308400D02*
X830012D01*
G01X833612Y-316400D02*
Y-308400D01*
G01X837812D02*
Y-316400D01*
G01Y-312400D02*
X833612D01*
G01X843712Y-316400D02*
X844412Y-316267D01*
X845212Y-315867D01*
X845712Y-315200D01*
X845912Y-314267D01*
X845712Y-313334D01*
X845112Y-312533D01*
X844212Y-312133D01*
X843212D01*
X842612Y-311867D01*
X842112Y-311200D01*
X841912Y-310267D01*
X842212Y-309333D01*
X842912Y-308667D01*
X843712Y-308400D01*
X844512Y-308667D01*
X845212Y-309333D01*
X845512Y-310267D01*
X845312Y-311200D01*
X844812Y-311867D01*
X844212Y-312133D01*
X843212D01*
X842312Y-312533D01*
X841712Y-313334D01*
X841512Y-314267D01*
X841712Y-315200D01*
X842212Y-315867D01*
X843012Y-316267D01*
X843712Y-316400D01*
G01X853912Y-309067D02*
X853312Y-308667D01*
X852612Y-308400D01*
X851812D01*
X850912Y-308800D01*
X850212Y-309467D01*
X849712Y-310267D01*
X849312Y-311600D01*
X849212Y-312800D01*
X849412Y-314000D01*
X849712Y-314800D01*
X850312Y-315600D01*
X851012Y-316133D01*
X851712Y-316400D01*
X852412D01*
X853112Y-316133D01*
X853712Y-315733D01*
X854212Y-315200D01*
G01X859712Y-308400D02*
X858912Y-308667D01*
X858312Y-309333D01*
X857912Y-310133D01*
X857612Y-311200D01*
X857512Y-312400D01*
X857612Y-313600D01*
X857912Y-314667D01*
X858312Y-315467D01*
X858912Y-316133D01*
X859712Y-316400D01*
X860512Y-316133D01*
X861112Y-315467D01*
X861512Y-314667D01*
X861812Y-313600D01*
X861912Y-312400D01*
X861812Y-311200D01*
X861512Y-310133D01*
X861112Y-309333D01*
X860512Y-308667D01*
X859712Y-308400D01*
G01X799712Y-283400D02*
Y-291400D01*
G01X797412Y-283400D02*
X802012D01*
G01X805812Y-288067D02*
X806512Y-287133D01*
X807112Y-286600D01*
X807912Y-286333D01*
X808612Y-286600D01*
X809112Y-287133D01*
X809512Y-287933D01*
X809612Y-288867D01*
X809512Y-289667D01*
X809112Y-290467D01*
X808512Y-291133D01*
X807812Y-291400D01*
X807012Y-291133D01*
X806312Y-290334D01*
X805912Y-289133D01*
X805812Y-287800D01*
X806012Y-286067D01*
X806312Y-285133D01*
X806812Y-284200D01*
X807512Y-283533D01*
X808212Y-283400D01*
X808912Y-283667D01*
X809412Y-284333D01*
G01X813112Y-291400D02*
Y-283400D01*
X815712Y-290067D01*
X818312Y-283400D01*
Y-291400D01*
G01X820712Y-294067D02*
X826712D01*
G01X831712Y-283400D02*
Y-291400D01*
G01X829412Y-283400D02*
X834012D01*
G01X838312Y-291400D02*
Y-286067D01*
G01Y-287133D02*
X838812Y-286600D01*
X839312Y-286200D01*
X840012Y-286067D01*
X840512Y-286200D01*
X841112Y-286600D01*
G01X849512Y-291400D02*
Y-286067D01*
G01Y-287000D02*
X849112Y-286467D01*
X848512Y-286200D01*
X847812Y-286067D01*
X847112Y-286333D01*
X846512Y-286867D01*
X846112Y-287667D01*
X845912Y-288733D01*
X846112Y-289800D01*
X846512Y-290600D01*
X847112Y-291133D01*
X847812Y-291400D01*
X848512Y-291267D01*
X849112Y-290867D01*
X849512Y-290334D01*
G01X853612Y-293800D02*
X854212Y-294067D01*
X855012Y-293800D01*
X855512Y-293267D01*
X855912Y-292600D01*
X856512Y-290467D01*
X857812Y-286067D01*
G01X854612D02*
X856512Y-290467D01*
G01X860712Y-294067D02*
X866712D01*
G01X872512Y-287133D02*
X872912Y-286733D01*
X873212Y-286067D01*
X873412Y-285133D01*
X873212Y-284333D01*
X872812Y-283800D01*
X872112Y-283400D01*
X869412D01*
Y-291400D01*
X872712D01*
X873412Y-290867D01*
X873812Y-290067D01*
X874012Y-289133D01*
X873812Y-288200D01*
X873212Y-287400D01*
X872512Y-287133D01*
X869412D01*
G01X877712Y-291400D02*
Y-283400D01*
X880112D01*
X880912Y-283800D01*
X881512Y-284733D01*
X881712Y-285800D01*
X881512Y-286867D01*
X881012Y-287667D01*
X880112Y-288067D01*
X877712D01*
G01X896912Y-334067D02*
X896312Y-333667D01*
X895612Y-333400D01*
X894812D01*
X893912Y-333800D01*
X893212Y-334467D01*
X892712Y-335267D01*
X892312Y-336600D01*
X892212Y-337800D01*
X892412Y-339000D01*
X892712Y-339800D01*
X893312Y-340600D01*
X894012Y-341133D01*
X894712Y-341400D01*
X895412D01*
X896112Y-341133D01*
X896712Y-340733D01*
X897212Y-340200D01*
G01X922212Y-341400D02*
Y-333400D01*
X921012Y-335000D01*
G01Y-341400D02*
X923412D01*
G01X928312Y-338067D02*
X929012Y-337133D01*
X929612Y-336600D01*
X930412Y-336333D01*
X931112Y-336600D01*
X931612Y-337133D01*
X932012Y-337933D01*
X932112Y-338867D01*
X932012Y-339667D01*
X931612Y-340467D01*
X931012Y-341133D01*
X930312Y-341400D01*
X929512Y-341133D01*
X928812Y-340334D01*
X928412Y-339133D01*
X928312Y-337800D01*
X928512Y-336067D01*
X928812Y-335133D01*
X929312Y-334200D01*
X930012Y-333533D01*
X930712Y-333400D01*
X931412Y-333667D01*
X931912Y-334333D01*
G54D43*
X463859Y176650D03*
X508859D03*
X1333938D03*
X1378938D03*
G54D25*
X306772Y67913D03*
X612047D03*
X1176851D03*
X1482126D03*
G54D34*
X392776Y32264D03*
X383642Y50375D03*
Y70060D03*
Y88564D03*
X411673Y32264D03*
X430571D03*
X439744Y50375D03*
Y70060D03*
Y88564D03*
X532934Y50375D03*
Y70060D03*
Y88564D03*
X542068Y32264D03*
X560965D03*
X579863D03*
X589036Y50375D03*
Y70060D03*
Y88564D03*
X1262855Y32264D03*
X1253721Y50375D03*
Y70060D03*
Y88564D03*
X1281752Y32264D03*
X1300650D03*
X1309823Y50375D03*
Y70060D03*
Y88564D03*
X1412146Y32264D03*
X1403012Y50375D03*
Y70060D03*
Y88564D03*
X1431043Y32264D03*
X1449941D03*
X1459114Y50375D03*
Y70060D03*
Y88564D03*
G54D16*
X40827Y29528D03*
Y147638D03*
G54D26*
X332000Y128960D03*
Y136440D03*
X340473Y129060D03*
Y136540D03*
X617949Y131360D03*
Y138840D03*
X626173Y131360D03*
Y138840D03*
X1206000Y128760D03*
Y136240D03*
X1214100Y128860D03*
Y136340D03*
X1495800Y135760D03*
Y143240D03*
X1487600Y135760D03*
Y143240D03*
G54D35*
X398307Y40511D03*
X396732Y72795D03*
X417205Y40511D03*
X407756D03*
X414055D03*
X410906D03*
X420354D03*
X401457D03*
X404606D03*
X421929Y72795D03*
X418780D03*
X399882D03*
X406181D03*
X415630D03*
X412480D03*
X409331D03*
X403032D03*
X426654Y40511D03*
X423504D03*
X425079Y72795D03*
X557048Y40512D03*
X547599D03*
X560198D03*
X550749D03*
X553898D03*
X546024Y72796D03*
X549174D03*
X555473D03*
X558623D03*
X552324D03*
X575946Y40512D03*
X566497D03*
X563347D03*
X572796D03*
X569646D03*
X574371Y72796D03*
X571221D03*
X568072D03*
X564922D03*
X561772D03*
X1268386Y40512D03*
X1271536D03*
X1274685D03*
X1266811Y72796D03*
X1269961D03*
X1273111D03*
X1296733Y40512D03*
X1287284D03*
X1277835D03*
X1284134D03*
X1280985D03*
X1293583D03*
X1290433D03*
X1295158Y72796D03*
X1292008D03*
X1288859D03*
X1276260D03*
X1285709D03*
X1282559D03*
X1279410D03*
X1427127Y40511D03*
X1417678D03*
X1433426D03*
X1430277D03*
X1420828D03*
X1423977D03*
X1416103Y72795D03*
X1419253D03*
X1425552D03*
X1435001D03*
X1431851D03*
X1428702D03*
X1422403D03*
X1446025Y40511D03*
X1436576D03*
X1442875D03*
X1439725D03*
X1444450Y72795D03*
X1441300D03*
X1438151D03*
G54D17*
X44528Y41339D03*
Y53150D03*
X56339Y41339D03*
Y53150D03*
X44528Y64961D03*
Y76772D03*
X56339Y64961D03*
Y76772D03*
X44528Y88583D03*
Y100394D03*
X56339Y88583D03*
Y100394D03*
X44528Y112205D03*
Y124016D03*
X56339Y112205D03*
Y124016D03*
X44528Y135827D03*
G54D44*
X506024Y8268D03*
X688543D03*
X1376103D03*
X1558622D03*
G54D18*
X56339Y135827D03*
G54D45*
X503859Y151650D03*
X1373938D03*
G54D36*
X392795Y56653D03*
X542087Y56654D03*
X655453Y132244D03*
X702697D03*
X730295D03*
X777539D03*
X1262874Y56654D03*
X1412166Y56653D03*
X1525531Y132244D03*
X1572775D03*
X1600374D03*
X1647618D03*
G54D27*
X343780Y11810D03*
Y19684D03*
Y27558D03*
X335906Y11810D03*
Y19684D03*
Y27558D03*
X343780Y43306D03*
Y51180D03*
X335906Y43306D03*
Y51180D03*
X343780Y59054D03*
X367402Y11810D03*
Y19684D03*
Y27558D03*
X359528Y11810D03*
Y19684D03*
Y27558D03*
X367402Y43306D03*
Y51180D03*
X359528Y43306D03*
Y51180D03*
X367402Y59054D03*
X359528D03*
X1205984Y11810D03*
Y19684D03*
Y27558D03*
Y43306D03*
Y51180D03*
X1213858Y11810D03*
Y19684D03*
Y27558D03*
X1229606Y11810D03*
Y19684D03*
Y27558D03*
Y43306D03*
Y51180D03*
X1213858Y43306D03*
Y51180D03*
X1229606Y59054D03*
X1213858D03*
X1237480Y11810D03*
Y19684D03*
Y27558D03*
Y43306D03*
Y51180D03*
Y59054D03*
G54D19*
X62521Y191536D03*
X102521D03*
X142521D03*
X182521D03*
G54D46*
X639283Y108622D03*
Y167677D03*
X793693Y108622D03*
Y167677D03*
X1509362Y108622D03*
Y167677D03*
X1663772Y108622D03*
Y167677D03*
G54D28*
X351654Y37400D03*
X1221732D03*
G54D37*
X383642Y40532D03*
Y79902D03*
X396122Y99587D03*
X383642Y119272D03*
Y158642D03*
X417382Y99587D03*
X405964Y178327D03*
X439744Y99587D03*
Y138957D03*
Y178327D03*
X532934Y40532D03*
Y79902D03*
Y119272D03*
Y158642D03*
X545414Y99587D03*
X555256Y178327D03*
X566674Y99587D03*
X589036D03*
Y138957D03*
Y178327D03*
X1253721Y40532D03*
Y79902D03*
Y119272D03*
Y158642D03*
X1266201Y99587D03*
X1276043Y178327D03*
X1287461Y99587D03*
X1309823D03*
Y138957D03*
Y178327D03*
X1403012Y40532D03*
Y79902D03*
Y119272D03*
Y158642D03*
X1415492Y99587D03*
X1436752D03*
X1425334Y178327D03*
X1459114Y99587D03*
Y138957D03*
Y178327D03*
G54D38*
X430591Y56653D03*
X579883Y56654D03*
X1300670D03*
X1449962Y56653D03*
G54D47*
X641212Y132244D03*
X791764D03*
X1511291D03*
X1661843D03*
G54D29*
X335906Y59054D03*
X1205984D03*
G54D48*
X660965Y101968D03*
X664114D03*
X667264D03*
X670414D03*
X673563D03*
X659390Y111850D03*
X662540D03*
X665689D03*
X668839D03*
X671988D03*
X675138D03*
X676713Y101968D03*
X679862D03*
X683012D03*
X686162D03*
X689311D03*
X692461D03*
X695610D03*
X678288Y111850D03*
X681437D03*
X684587D03*
X687736D03*
X690886D03*
X694036D03*
X697185D03*
X698760Y101968D03*
X735807D03*
X738956D03*
X742106D03*
X734232Y111850D03*
X737382D03*
X740531D03*
X743681D03*
X745256Y101968D03*
X748405D03*
X751555D03*
X754704D03*
X757854D03*
X761004D03*
X764153D03*
X767303D03*
X746830Y111850D03*
X749980D03*
X753130D03*
X756279D03*
X759429D03*
X762578D03*
X765728D03*
X770452Y101968D03*
X773602D03*
X768878Y111850D03*
X772027D03*
X1531043Y101968D03*
X1534192D03*
X1537342D03*
X1540492D03*
X1543641D03*
X1546791D03*
X1549940D03*
X1529468Y111850D03*
X1532618D03*
X1535767D03*
X1538917D03*
X1542066D03*
X1545216D03*
X1548366D03*
X1553090Y101968D03*
X1556240D03*
X1559389D03*
X1562539D03*
X1565688D03*
X1568838D03*
X1551515Y111850D03*
X1554665D03*
X1557814D03*
X1560964D03*
X1564114D03*
X1567263D03*
X1605886Y101968D03*
X1609035D03*
X1612185D03*
X1615335D03*
X1618484D03*
X1604311Y111850D03*
X1607461D03*
X1610610D03*
X1613760D03*
X1616909D03*
X1621634Y101968D03*
X1624783D03*
X1627933D03*
X1631083D03*
X1634232D03*
X1637382D03*
X1640531D03*
X1620059Y111850D03*
X1623209D03*
X1626358D03*
X1629508D03*
X1632657D03*
X1635807D03*
X1638957D03*
X1642106D03*
X1643681Y101968D03*
G54D39*
X439744Y60217D03*
X589036D03*
X1309823D03*
X1459114D03*
G54D49*
X670425Y82539D03*
X679874D03*
X689323D03*
X745268D03*
X754716D03*
X764165D03*
X1540504D03*
X1549953D03*
X1559402D03*
X1615347D03*
X1624795D03*
X1634244D03*
M02*
